(kicad_pcb
	(version 20260206)
	(generator "pcbnew")
	(generator_version "10.0")
	(general
		(thickness 1.6)
		(legacy_teardrops no)
	)
	(paper "A4")
	(title_block
		(title "01162023_DA0F0TEBIF0_F0T_Expander_BD_F_brd_V02_OCP.brd")
		(comment 1 "Grand Teton / footprints 6348-6354 of 9728")
	)
	(layers
		(0 "F.Cu" signal "TOP")
		(4 "In1.Cu" signal "GND")
		(6 "In2.Cu" signal "VCC")
		(8 "In3.Cu" signal "VCC1")
		(10 "In4.Cu" signal "GND1")
		(12 "In5.Cu" signal "IN1")
		(14 "In6.Cu" signal "GND2")
		(16 "In7.Cu" signal "IN2")
		(18 "In8.Cu" signal "GND3")
		(20 "In9.Cu" signal "IN3")
		(22 "In10.Cu" signal "GND4")
		(24 "In11.Cu" signal "IN4")
		(26 "In12.Cu" signal "GND5")
		(28 "In13.Cu" signal "IN5")
		(30 "In14.Cu" signal "GND6")
		(32 "In15.Cu" signal "IN6")
		(34 "In16.Cu" signal "GND7")
		(2 "B.Cu" signal "BOTTOM")
		(9 "F.Adhes" user "F.Adhesive")
		(11 "B.Adhes" user "B.Adhesive")
		(13 "F.Paste" user "Package Geometry/Pastemask Top")
		(15 "B.Paste" user "Package Geometry/Pastemask Bottom")
		(5 "F.SilkS" user "Ref Des/Silkscreen Top")
		(7 "B.SilkS" user "Ref Des/Silkscreen Bottom")
		(1 "F.Mask" user "Board Geometry/Soldermask Top")
		(3 "B.Mask" user "Board Geometry/Soldermask Bottom")
		(17 "Dwgs.User" user "User.Drawings")
		(19 "Cmts.User" user "User.Comments")
		(21 "Eco1.User" user "User.Eco1")
		(23 "Eco2.User" user "User.Eco2")
		(25 "Edge.Cuts" user "Board Geometry/Outline")
		(27 "Margin" user)
		(31 "F.CrtYd" user "Package Geometry/Place Bound Top")
		(29 "B.CrtYd" user "Package Geometry/Place Bound Bottom")
		(35 "F.Fab" user "Ref Des/Assembly Top")
		(33 "B.Fab" user "Ref Des/Assembly Bottom")
	)
	(footprint ""
		(layer "F.Cu")
		(at 376.936 -184.785 180)
		(property "Reference" "R4616"
			(at 0 0 180)
			(layer "F.SilkS")
			(hide yes)
			(effects
				(font
					(size 1.27 1.27)
				)
			)
		)
		(property "Value" ""
			(at 0 0 180)
			(layer "F.Fab")
			(effects
				(font
					(size 1.27 1.27)
				)
			)
		)
		(duplicate_pad_numbers_are_jumpers no)
		(fp_line
			(start 0.7874 0.4064)
			(end -0.7874 0.4064)
			(stroke
				(width 0.1524)
				(type default)
			)
			(layer "F.SilkS")
		)
		(fp_line
			(start 0.7874 -0.4064)
			(end 0.7874 0.4064)
			(stroke
				(width 0.1524)
				(type default)
			)
			(layer "F.SilkS")
		)
		(fp_line
			(start -0.7874 0.4064)
			(end -0.7874 -0.4064)
			(stroke
				(width 0.1524)
				(type default)
			)
			(layer "F.SilkS")
		)
		(fp_line
			(start -0.7874 -0.4064)
			(end 0.7874 -0.4064)
			(stroke
				(width 0.1524)
				(type default)
			)
			(layer "F.SilkS")
		)
		(fp_line
			(start 0.67945 0.3048)
			(end 0.120396 0.3048)
			(stroke
				(width 0.1)
				(type default)
			)
			(layer "F.Fab")
		)
		(fp_line
			(start 0.67945 -0.3048)
			(end 0.67945 0.3048)
			(stroke
				(width 0.1)
				(type default)
			)
			(layer "F.Fab")
		)
		(fp_line
			(start 0.12065 -0.2794)
			(end 0.12065 -0.3048)
			(stroke
				(width 0.1)
				(type default)
			)
			(layer "F.Fab")
		)
		(fp_line
			(start 0.12065 -0.3048)
			(end 0.67945 -0.3048)
			(stroke
				(width 0.1)
				(type default)
			)
			(layer "F.Fab")
		)
		(fp_line
			(start 0.120396 0.3048)
			(end 0.120396 0.2794)
			(stroke
				(width 0.1)
				(type default)
			)
			(layer "F.Fab")
		)
		(fp_line
			(start 0.120396 0.2794)
			(end -0.12065 0.2794)
			(stroke
				(width 0.1)
				(type default)
			)
			(layer "F.Fab")
		)
		(fp_line
			(start -0.12065 0.3048)
			(end -0.67945 0.3048)
			(stroke
				(width 0.1)
				(type default)
			)
			(layer "F.Fab")
		)
		(fp_line
			(start -0.12065 0.2794)
			(end -0.12065 0.3048)
			(stroke
				(width 0.1)
				(type default)
			)
			(layer "F.Fab")
		)
		(fp_line
			(start -0.12065 -0.2794)
			(end 0.12065 -0.2794)
			(stroke
				(width 0.1)
				(type default)
			)
			(layer "F.Fab")
		)
		(fp_line
			(start -0.12065 -0.305054)
			(end -0.12065 -0.2794)
			(stroke
				(width 0.1)
				(type default)
			)
			(layer "F.Fab")
		)
		(fp_line
			(start -0.67945 0.3048)
			(end -0.67945 -0.305054)
			(stroke
				(width 0.1)
				(type default)
			)
			(layer "F.Fab")
		)
		(fp_line
			(start -0.67945 -0.305054)
			(end -0.12065 -0.305054)
			(stroke
				(width 0.1)
				(type default)
			)
			(layer "F.Fab")
		)
		(pad "1" smd circle
			(at -0.40005 0 180)
			(size 0 0)
			(layers "F.Cu" "F.Mask" "F.Paste")
			(net "NIC1_PEX_PWR_EN_R")
		)
		(pad "2" smd circle
			(at 0.40005 0 180)
			(size 0 0)
			(layers "F.Cu" "F.Mask" "F.Paste")
			(net "GND")
		)
	)
	(footprint ""
		(layer "F.Cu")
		(at 358.013 -222.504)
		(property "Reference" "R3639"
			(at 0 0 0)
			(layer "F.SilkS")
			(hide yes)
			(effects
				(font
					(size 1.27 1.27)
				)
			)
		)
		(property "Value" ""
			(at 0 0 0)
			(layer "F.Fab")
			(effects
				(font
					(size 1.27 1.27)
				)
			)
		)
		(duplicate_pad_numbers_are_jumpers no)
		(fp_line
			(start -0.7874 -0.4064)
			(end 0.7874 -0.4064)
			(stroke
				(width 0.1524)
				(type default)
			)
			(layer "F.SilkS")
		)
		(fp_line
			(start -0.7874 0.4064)
			(end -0.7874 -0.4064)
			(stroke
				(width 0.1524)
				(type default)
			)
			(layer "F.SilkS")
		)
		(fp_line
			(start 0.7874 -0.4064)
			(end 0.7874 0.4064)
			(stroke
				(width 0.1524)
				(type default)
			)
			(layer "F.SilkS")
		)
		(fp_line
			(start 0.7874 0.4064)
			(end -0.7874 0.4064)
			(stroke
				(width 0.1524)
				(type default)
			)
			(layer "F.SilkS")
		)
		(fp_line
			(start -0.67945 -0.305054)
			(end -0.12065 -0.305054)
			(stroke
				(width 0.1)
				(type default)
			)
			(layer "F.Fab")
		)
		(fp_line
			(start -0.67945 0.3048)
			(end -0.67945 -0.305054)
			(stroke
				(width 0.1)
				(type default)
			)
			(layer "F.Fab")
		)
		(fp_line
			(start -0.12065 -0.305054)
			(end -0.12065 -0.2794)
			(stroke
				(width 0.1)
				(type default)
			)
			(layer "F.Fab")
		)
		(fp_line
			(start -0.12065 -0.2794)
			(end 0.12065 -0.2794)
			(stroke
				(width 0.1)
				(type default)
			)
			(layer "F.Fab")
		)
		(fp_line
			(start -0.12065 0.2794)
			(end -0.12065 0.3048)
			(stroke
				(width 0.1)
				(type default)
			)
			(layer "F.Fab")
		)
		(fp_line
			(start -0.12065 0.3048)
			(end -0.67945 0.3048)
			(stroke
				(width 0.1)
				(type default)
			)
			(layer "F.Fab")
		)
		(fp_line
			(start 0.120396 0.2794)
			(end -0.12065 0.2794)
			(stroke
				(width 0.1)
				(type default)
			)
			(layer "F.Fab")
		)
		(fp_line
			(start 0.120396 0.3048)
			(end 0.120396 0.2794)
			(stroke
				(width 0.1)
				(type default)
			)
			(layer "F.Fab")
		)
		(fp_line
			(start 0.12065 -0.3048)
			(end 0.67945 -0.3048)
			(stroke
				(width 0.1)
				(type default)
			)
			(layer "F.Fab")
		)
		(fp_line
			(start 0.12065 -0.2794)
			(end 0.12065 -0.3048)
			(stroke
				(width 0.1)
				(type default)
			)
			(layer "F.Fab")
		)
		(fp_line
			(start 0.67945 -0.3048)
			(end 0.67945 0.3048)
			(stroke
				(width 0.1)
				(type default)
			)
			(layer "F.Fab")
		)
		(fp_line
			(start 0.67945 0.3048)
			(end 0.120396 0.3048)
			(stroke
				(width 0.1)
				(type default)
			)
			(layer "F.Fab")
		)
		(pad "1" smd circle
			(at -0.40005 0)
			(size 0 0)
			(layers "F.Cu" "F.Mask" "F.Paste")
			(net "RST_NIC4_PERST_N")
		)
		(pad "2" smd circle
			(at 0.40005 0)
			(size 0 0)
			(layers "F.Cu" "F.Mask" "F.Paste")
			(net "RST_NIC4_PERST_R_N")
		)
	)
	(footprint ""
		(layer "F.Cu")
		(at 93.350842 -350.098614 90)
		(property "Reference" "C98"
			(at 0 0 90)
			(layer "F.SilkS")
			(hide yes)
			(effects
				(font
					(size 1.27 1.27)
				)
			)
		)
		(property "Value" ""
			(at 0 0 90)
			(layer "F.Fab")
			(effects
				(font
					(size 1.27 1.27)
				)
			)
		)
		(duplicate_pad_numbers_are_jumpers no)
		(fp_line
			(start 0.299974 -0.150114)
			(end 0.299974 0.150114)
			(stroke
				(width 0.1)
				(type default)
			)
			(layer "F.Fab")
		)
		(fp_line
			(start -0.299974 -0.150114)
			(end 0.299974 -0.150114)
			(stroke
				(width 0.1)
				(type default)
			)
			(layer "F.Fab")
		)
		(fp_line
			(start 0.299974 0.150114)
			(end -0.299974 0.150114)
			(stroke
				(width 0.1)
				(type default)
			)
			(layer "F.Fab")
		)
		(fp_line
			(start -0.299974 0.150114)
			(end -0.299974 -0.150114)
			(stroke
				(width 0.1)
				(type default)
			)
			(layer "F.Fab")
		)
		(pad "1" smd rect
			(at -0.2667 0 90)
			(size 0.3048 0.381)
			(layers "F.Cu" "F.Mask" "F.Paste")
			(net "P5E_PEX0_STN5_TX_DN<95>")
		)
		(pad "2" smd rect
			(at 0.2667 0 90)
			(size 0.3048 0.381)
			(layers "F.Cu" "F.Mask" "F.Paste")
			(net "P5E_PEX0_STN5_TX_C_DN<95>")
		)
	)
	(footprint ""
		(layer "F.Cu")
		(at 145.457926 -27.006296 -90)
		(property "Reference" "PR7109"
			(at 0 0 270)
			(layer "F.SilkS")
			(hide yes)
			(effects
				(font
					(size 1.27 1.27)
				)
			)
		)
		(property "Value" ""
			(at 0 0 270)
			(layer "F.Fab")
			(effects
				(font
					(size 1.27 1.27)
				)
			)
		)
		(duplicate_pad_numbers_are_jumpers no)
		(fp_line
			(start -0.7874 0.4064)
			(end -0.7874 -0.4064)
			(stroke
				(width 0.1524)
				(type default)
			)
			(layer "F.SilkS")
		)
		(fp_line
			(start 0.7874 0.4064)
			(end -0.7874 0.4064)
			(stroke
				(width 0.1524)
				(type default)
			)
			(layer "F.SilkS")
		)
		(fp_line
			(start -0.7874 -0.4064)
			(end 0.7874 -0.4064)
			(stroke
				(width 0.1524)
				(type default)
			)
			(layer "F.SilkS")
		)
		(fp_line
			(start 0.7874 -0.4064)
			(end 0.7874 0.4064)
			(stroke
				(width 0.1524)
				(type default)
			)
			(layer "F.SilkS")
		)
		(fp_line
			(start -0.67945 0.3048)
			(end -0.67945 -0.305054)
			(stroke
				(width 0.1)
				(type default)
			)
			(layer "F.Fab")
		)
		(fp_line
			(start -0.12065 0.3048)
			(end -0.67945 0.3048)
			(stroke
				(width 0.1)
				(type default)
			)
			(layer "F.Fab")
		)
		(fp_line
			(start 0.120396 0.3048)
			(end 0.120396 0.2794)
			(stroke
				(width 0.1)
				(type default)
			)
			(layer "F.Fab")
		)
		(fp_line
			(start 0.67945 0.3048)
			(end 0.120396 0.3048)
			(stroke
				(width 0.1)
				(type default)
			)
			(layer "F.Fab")
		)
		(fp_line
			(start -0.12065 0.2794)
			(end -0.12065 0.3048)
			(stroke
				(width 0.1)
				(type default)
			)
			(layer "F.Fab")
		)
		(fp_line
			(start 0.120396 0.2794)
			(end -0.12065 0.2794)
			(stroke
				(width 0.1)
				(type default)
			)
			(layer "F.Fab")
		)
		(fp_line
			(start -0.12065 -0.2794)
			(end 0.12065 -0.2794)
			(stroke
				(width 0.1)
				(type default)
			)
			(layer "F.Fab")
		)
		(fp_line
			(start 0.12065 -0.2794)
			(end 0.12065 -0.3048)
			(stroke
				(width 0.1)
				(type default)
			)
			(layer "F.Fab")
		)
		(fp_line
			(start 0.12065 -0.3048)
			(end 0.67945 -0.3048)
			(stroke
				(width 0.1)
				(type default)
			)
			(layer "F.Fab")
		)
		(fp_line
			(start 0.67945 -0.3048)
			(end 0.67945 0.3048)
			(stroke
				(width 0.1)
				(type default)
			)
			(layer "F.Fab")
		)
		(fp_line
			(start -0.67945 -0.305054)
			(end -0.12065 -0.305054)
			(stroke
				(width 0.1)
				(type default)
			)
			(layer "F.Fab")
		)
		(fp_line
			(start -0.12065 -0.305054)
			(end -0.12065 -0.2794)
			(stroke
				(width 0.1)
				(type default)
			)
			(layer "F.Fab")
		)
		(pad "1" smd circle
			(at -0.40005 0 270)
			(size 0 0)
			(layers "F.Cu" "F.Mask" "F.Paste")
			(net "P3V3_SSD5_CO_MODE")
		)
		(pad "2" smd circle
			(at 0.40005 0 270)
			(size 0 0)
			(layers "F.Cu" "F.Mask" "F.Paste")
			(net "GND")
		)
	)
	(footprint ""
		(layer "F.Cu")
		(at 90.639392 -293.47287 -90)
		(property "Reference" "U313"
			(at -0.535178 -4.855718 90)
			(unlocked yes)
			(layer "F.SilkS")
			(effects
				(font
					(size 0.7874 0.5842)
					(thickness 0.1524)
				)
			)
		)
		(property "Value" ""
			(at 0 0 270)
			(layer "F.Fab")
			(effects
				(font
					(size 1.27 1.27)
				)
			)
		)
		(duplicate_pad_numbers_are_jumpers no)
		(fp_line
			(start -1.463548 1.549908)
			(end -1.463548 -1.549908)
			(stroke
				(width 0.1524)
				(type default)
			)
			(layer "F.SilkS")
		)
		(fp_line
			(start 1.463548 1.549908)
			(end -1.463548 1.549908)
			(stroke
				(width 0.1524)
				(type default)
			)
			(layer "F.SilkS")
		)
		(fp_line
			(start 0 -0.762)
			(end 0.762 -1.549908)
			(stroke
				(width 0.1524)
				(type default)
			)
			(layer "F.SilkS")
		)
		(fp_line
			(start -1.463548 -1.549908)
			(end -0.787908 -1.549908)
			(stroke
				(width 0.1524)
				(type default)
			)
			(layer "F.SilkS")
		)
		(fp_line
			(start -0.787908 -1.549908)
			(end 0 -0.762)
			(stroke
				(width 0.1524)
				(type default)
			)
			(layer "F.SilkS")
		)
		(fp_line
			(start 0.762 -1.549908)
			(end 1.463548 -1.549908)
			(stroke
				(width 0.1524)
				(type default)
			)
			(layer "F.SilkS")
		)
		(fp_line
			(start 1.463548 -1.549908)
			(end 1.463548 1.549908)
			(stroke
				(width 0.1524)
				(type default)
			)
			(layer "F.SilkS")
		)
		(fp_poly
			(pts
				(xy -3.4798 -1.359916) (xy -2.86004 -1.050036) (xy -3.4798 -0.740156)
			)
			(stroke
				(width 0)
				(type default)
			)
			(fill yes)
			(layer "F.SilkS")
		)
		(fp_line
			(start -1.549908 1.549908)
			(end -1.549908 -1.549908)
			(stroke
				(width 0.1)
				(type default)
			)
			(layer "F.Fab")
		)
		(fp_line
			(start 1.549908 1.549908)
			(end -1.549908 1.549908)
			(stroke
				(width 0.1)
				(type default)
			)
			(layer "F.Fab")
		)
		(fp_line
			(start -1.549908 -1.549908)
			(end 1.549908 -1.549908)
			(stroke
				(width 0.1)
				(type default)
			)
			(layer "F.Fab")
		)
		(fp_line
			(start 1.549908 -1.549908)
			(end 1.549908 1.549908)
			(stroke
				(width 0.1)
				(type default)
			)
			(layer "F.Fab")
		)
		(fp_poly
			(pts
				(xy -3.4798 -1.359916) (xy -2.86004 -1.050036) (xy -3.4798 -0.740156)
			)
			(stroke
				(width 0)
				(type default)
			)
			(fill yes)
			(layer "F.Fab")
		)
		(pad "1" smd rect
			(at -2.175002 -1.050036)
			(size 0.6096 1.1684)
			(layers "F.Cu" "F.Mask" "F.Paste")
			(net "P1V8_PEX")
		)
		(pad "2" smd rect
			(at -2.175002 -0.32512)
			(size 0.4318 1.1684)
			(layers "F.Cu" "F.Mask" "F.Paste")
			(net "I2C_PEX0_HOST_R_SCL")
		)
		(pad "3" smd rect
			(at -2.175002 0.32512)
			(size 0.4318 1.1684)
			(layers "F.Cu" "F.Mask" "F.Paste")
			(net "I2C_PEX0_HOST_R_SDA")
		)
		(pad "4" smd rect
			(at -2.175002 1.050036)
			(size 0.6096 1.1684)
			(layers "F.Cu" "F.Mask" "F.Paste")
			(net "GND")
		)
		(pad "5" smd rect
			(at 2.175002 1.050036)
			(size 0.6096 1.1684)
			(layers "F.Cu" "F.Mask" "F.Paste")
			(net "PWRGD_P1V8_PEX0_R")
		)
		(pad "6" smd rect
			(at 2.175002 0.32512)
			(size 0.4318 1.1684)
			(layers "F.Cu" "F.Mask" "F.Paste")
			(net "SMB_PEX0_HOST_LS_SDA")
		)
		(pad "7" smd rect
			(at 2.175002 -0.32512)
			(size 0.4318 1.1684)
			(layers "F.Cu" "F.Mask" "F.Paste")
			(net "SMB_PEX0_HOST_LS_SCL")
		)
		(pad "8" smd rect
			(at 2.175002 -1.050036)
			(size 0.6096 1.1684)
			(layers "F.Cu" "F.Mask" "F.Paste")
			(net "P3V3_AUX")
		)
	)
	(footprint ""
		(layer "F.Cu")
		(at 129.690114 -253.178564 180)
		(property "Reference" "R826"
			(at 0 0 180)
			(layer "F.SilkS")
			(hide yes)
			(effects
				(font
					(size 1.27 1.27)
				)
			)
		)
		(property "Value" ""
			(at 0 0 180)
			(layer "F.Fab")
			(effects
				(font
					(size 1.27 1.27)
				)
			)
		)
		(duplicate_pad_numbers_are_jumpers no)
		(fp_line
			(start 0.7874 0.4064)
			(end -0.7874 0.4064)
			(stroke
				(width 0.1524)
				(type default)
			)
			(layer "F.SilkS")
		)
		(fp_line
			(start 0.7874 -0.4064)
			(end 0.7874 0.4064)
			(stroke
				(width 0.1524)
				(type default)
			)
			(layer "F.SilkS")
		)
		(fp_line
			(start -0.7874 0.4064)
			(end -0.7874 -0.4064)
			(stroke
				(width 0.1524)
				(type default)
			)
			(layer "F.SilkS")
		)
		(fp_line
			(start -0.7874 -0.4064)
			(end 0.7874 -0.4064)
			(stroke
				(width 0.1524)
				(type default)
			)
			(layer "F.SilkS")
		)
		(fp_line
			(start 0.67945 0.3048)
			(end 0.120396 0.3048)
			(stroke
				(width 0.1)
				(type default)
			)
			(layer "F.Fab")
		)
		(fp_line
			(start 0.67945 -0.3048)
			(end 0.67945 0.3048)
			(stroke
				(width 0.1)
				(type default)
			)
			(layer "F.Fab")
		)
		(fp_line
			(start 0.12065 -0.2794)
			(end 0.12065 -0.3048)
			(stroke
				(width 0.1)
				(type default)
			)
			(layer "F.Fab")
		)
		(fp_line
			(start 0.12065 -0.3048)
			(end 0.67945 -0.3048)
			(stroke
				(width 0.1)
				(type default)
			)
			(layer "F.Fab")
		)
		(fp_line
			(start 0.120396 0.3048)
			(end 0.120396 0.2794)
			(stroke
				(width 0.1)
				(type default)
			)
			(layer "F.Fab")
		)
		(fp_line
			(start 0.120396 0.2794)
			(end -0.12065 0.2794)
			(stroke
				(width 0.1)
				(type default)
			)
			(layer "F.Fab")
		)
		(fp_line
			(start -0.12065 0.3048)
			(end -0.67945 0.3048)
			(stroke
				(width 0.1)
				(type default)
			)
			(layer "F.Fab")
		)
		(fp_line
			(start -0.12065 0.2794)
			(end -0.12065 0.3048)
			(stroke
				(width 0.1)
				(type default)
			)
			(layer "F.Fab")
		)
		(fp_line
			(start -0.12065 -0.2794)
			(end 0.12065 -0.2794)
			(stroke
				(width 0.1)
				(type default)
			)
			(layer "F.Fab")
		)
		(fp_line
			(start -0.12065 -0.305054)
			(end -0.12065 -0.2794)
			(stroke
				(width 0.1)
				(type default)
			)
			(layer "F.Fab")
		)
		(fp_line
			(start -0.67945 0.3048)
			(end -0.67945 -0.305054)
			(stroke
				(width 0.1)
				(type default)
			)
			(layer "F.Fab")
		)
		(fp_line
			(start -0.67945 -0.305054)
			(end -0.12065 -0.305054)
			(stroke
				(width 0.1)
				(type default)
			)
			(layer "F.Fab")
		)
		(pad "1" smd circle
			(at -0.40005 0 180)
			(size 0 0)
			(layers "F.Cu" "F.Mask" "F.Paste")
			(net "PWRGD_P0V8_PEX0_R")
		)
		(pad "2" smd circle
			(at 0.40005 0 180)
			(size 0 0)
			(layers "F.Cu" "F.Mask" "F.Paste")
			(net "P0V8_PEX0_AVRRDY")
		)
	)
	(footprint ""
		(layer "F.Cu")
		(at 38.832028 -147.969224 90)
		(property "Reference" "C846"
			(at 0 0 90)
			(layer "F.SilkS")
			(hide yes)
			(effects
				(font
					(size 1.27 1.27)
				)
			)
		)
		(property "Value" ""
			(at 0 0 90)
			(layer "F.Fab")
			(effects
				(font
					(size 1.27 1.27)
				)
			)
		)
		(duplicate_pad_numbers_are_jumpers no)
		(fp_line
			(start 1.524 -0.762)
			(end 1.524 0.762)
			(stroke
				(width 0.1524)
				(type default)
			)
			(layer "F.SilkS")
		)
		(fp_line
			(start -1.524 -0.762)
			(end 1.524 -0.762)
			(stroke
				(width 0.1524)
				(type default)
			)
			(layer "F.SilkS")
		)
		(fp_line
			(start 1.524 0.762)
			(end -1.524 0.762)
			(stroke
				(width 0.1524)
				(type default)
			)
			(layer "F.SilkS")
		)
		(fp_line
			(start -1.524 0.762)
			(end -1.524 -0.762)
			(stroke
				(width 0.1524)
				(type default)
			)
			(layer "F.SilkS")
		)
		(fp_line
			(start 1.1049 -0.724916)
			(end -1.1049 -0.724916)
			(stroke
				(width 0.1)
				(type default)
			)
			(layer "F.Fab")
		)
		(fp_line
			(start -1.1049 -0.724916)
			(end -1.1049 0.724916)
			(stroke
				(width 0.1)
				(type default)
			)
			(layer "F.Fab")
		)
		(fp_line
			(start 1.1049 0.724916)
			(end 1.1049 -0.724916)
			(stroke
				(width 0.1)
				(type default)
			)
			(layer "F.Fab")
		)
		(fp_line
			(start -1.1049 0.724916)
			(end 1.1049 0.724916)
			(stroke
				(width 0.1)
				(type default)
			)
			(layer "F.Fab")
		)
		(pad "1" smd rect
			(at -0.889 0 270)
			(size 1.016 1.27)
			(layers "F.Cu" "F.Mask" "F.Paste")
			(net "P12V_NIC0")
		)
		(pad "2" smd rect
			(at 0.889 0 270)
			(size 1.016 1.27)
			(layers "F.Cu" "F.Mask" "F.Paste")
			(net "GND")
		)
	)
)
